# BASEBOARD_FAB2 (Tioga Pass) — schematic netlist excerpt (pin names and nets, part order shuffled) for the footprints in the layout excerpt that follows; sources: Cadence DE-HDL packaged netlist, KiCad conversion of Wiwynn_Tioga_Pass_MB.brd

C1C19  CAP_A  22.0UF 4V 20% X6S  pkg 0603V  page 210 : A = PVSA_CPU1 ; B = GND
C5D38  CAP_A  22.0UF 4V 20% X6S  pkg 0603V  page 42 : A = PVCCMCP_CPU0 ; B = GND

(kicad_pcb
	(version 20260206)
	(generator "pcbnew")
	(generator_version "10.0")
	(general
		(thickness 1.6)
		(legacy_teardrops no)
	)
	(paper "A4")
	(title_block
		(title "Wiwynn_Tioga_Pass_MB.brd")
		(comment 1 "Tioga Pass / footprints 311-312 of 4770")
	)
	(layers
		(0 "F.Cu" signal "TOP")
		(4 "In1.Cu" signal "L2GND")
		(6 "In2.Cu" signal "L3")
		(8 "In3.Cu" signal "L4GND")
		(10 "In4.Cu" signal "L5")
		(12 "In5.Cu" signal "L6GND")
		(14 "In6.Cu" signal "L7VCC")
		(16 "In7.Cu" signal "L8VCC")
		(18 "In8.Cu" signal "L9GND")
		(20 "In9.Cu" signal "L10")
		(22 "In10.Cu" signal "L11GND")
		(24 "In11.Cu" signal "L12")
		(26 "In12.Cu" signal "L13GND")
		(2 "B.Cu" signal "BOTTOM")
		(9 "F.Adhes" user "F.Adhesive")
		(11 "B.Adhes" user "B.Adhesive")
		(13 "F.Paste" user "Package Geometry/Pastemask Top")
		(15 "B.Paste" user "Package Geometry/Pastemask Bottom")
		(5 "F.SilkS" user "Ref Des/Silkscreen Top")
		(7 "B.SilkS" user "Ref Des/Silkscreen Bottom")
		(1 "F.Mask" user "Board Geometry/Soldermask Top")
		(3 "B.Mask" user "Board Geometry/Soldermask Bottom")
		(17 "Dwgs.User" user "User.Drawings")
		(19 "Cmts.User" user "User.Comments")
		(21 "Eco1.User" user "User.Eco1")
		(23 "Eco2.User" user "User.Eco2")
		(25 "Edge.Cuts" user "Board Geometry/Outline")
		(27 "Margin" user)
		(31 "F.CrtYd" user "Package Geometry/Place Bound Top")
		(29 "B.CrtYd" user "Package Geometry/Place Bound Bottom")
		(35 "F.Fab" user "Ref Des/Assembly Top")
		(33 "B.Fab" user "Ref Des/Assembly Bottom")
	)
	(footprint ""
		(layer "F.Cu")
		(at 275.909024 -77.429614)
		(property "Reference" "C5D38"
			(at 0 0 0)
			(layer "F.SilkS")
			(hide yes)
			(effects
				(font
					(size 1.27 1.27)
				)
			)
		)
		(property "Value" ""
			(at 0 0 0)
			(layer "F.Fab")
			(effects
				(font
					(size 1.27 1.27)
				)
			)
		)
		(duplicate_pad_numbers_are_jumpers no)
		(fp_poly
			(pts
				(xy -0.4953 -0.2032) (xy 0.4953 -0.2032) (xy 0.4953 1.6002) (xy -0.4953 1.6002)
			)
			(stroke
				(width 0)
				(type default)
			)
			(fill no)
			(layer "F.CrtYd")
		)
		(fp_line
			(start -0.4953 -0.2032)
			(end 0.4953 -0.2032)
			(stroke
				(width 0.1)
				(type default)
			)
			(layer "F.Fab")
		)
		(fp_line
			(start -0.4953 1.6002)
			(end -0.4953 -0.2032)
			(stroke
				(width 0.1)
				(type default)
			)
			(layer "F.Fab")
		)
		(fp_line
			(start 0.4953 -0.2032)
			(end 0.4953 1.6002)
			(stroke
				(width 0.1)
				(type default)
			)
			(layer "F.Fab")
		)
		(fp_line
			(start 0.4953 1.6002)
			(end -0.4953 1.6002)
			(stroke
				(width 0.1)
				(type default)
			)
			(layer "F.Fab")
		)
		(pad "1" smd rect
			(at 0 0)
			(size 0.762 0.889)
			(layers "F.Cu" "F.Mask" "F.Paste")
			(net "PVCCMCP_CPU0")
		)
		(pad "2" smd rect
			(at 0 1.397)
			(size 0.762 0.889)
			(layers "F.Cu" "F.Mask" "F.Paste")
			(net "GND")
		)
		(zone
			(layer "F.Cu")
			(hatch none 0.5)
			(connect_pads
				(clearance 0)
			)
			(min_thickness 0.25)
			(keepout
				(tracks not_allowed)
				(vias allowed)
				(pads allowed)
				(copperpour not_allowed)
				(footprints allowed)
			)
			(placement
				(enabled no)
				(sheetname "")
			)
			(fill
				(thermal_gap 0.5)
				(thermal_bridge_width 0.5)
				(island_removal_mode 0)
			)
			(polygon
				(pts
					(xy 275.528024 -76.985114) (xy 276.290024 -76.985114) (xy 276.290024 -76.477114) (xy 275.528024 -76.477114)
				)
			)
		)
	)
	(footprint ""
		(layer "F.Cu")
		(at 49.4284 -93.7514)
		(property "Reference" "C1C19"
			(at 0 0 0)
			(layer "F.SilkS")
			(hide yes)
			(effects
				(font
					(size 1.27 1.27)
				)
			)
		)
		(property "Value" ""
			(at 0 0 0)
			(layer "F.Fab")
			(effects
				(font
					(size 1.27 1.27)
				)
			)
		)
		(duplicate_pad_numbers_are_jumpers no)
		(fp_poly
			(pts
				(xy -0.4953 -0.2032) (xy 0.4953 -0.2032) (xy 0.4953 1.6002) (xy -0.4953 1.6002)
			)
			(stroke
				(width 0)
				(type default)
			)
			(fill no)
			(layer "F.CrtYd")
		)
		(fp_line
			(start -0.4953 -0.2032)
			(end 0.4953 -0.2032)
			(stroke
				(width 0.1)
				(type default)
			)
			(layer "F.Fab")
		)
		(fp_line
			(start -0.4953 1.6002)
			(end -0.4953 -0.2032)
			(stroke
				(width 0.1)
				(type default)
			)
			(layer "F.Fab")
		)
		(fp_line
			(start 0.4953 -0.2032)
			(end 0.4953 1.6002)
			(stroke
				(width 0.1)
				(type default)
			)
			(layer "F.Fab")
		)
		(fp_line
			(start 0.4953 1.6002)
			(end -0.4953 1.6002)
			(stroke
				(width 0.1)
				(type default)
			)
			(layer "F.Fab")
		)
		(pad "1" smd rect
			(at 0 0)
			(size 0.762 0.889)
			(layers "F.Cu" "F.Mask" "F.Paste")
			(net "PVSA_CPU1")
		)
		(pad "2" smd rect
			(at 0 1.397)
			(size 0.762 0.889)
			(layers "F.Cu" "F.Mask" "F.Paste")
			(net "GND")
		)
		(zone
			(layer "F.Cu")
			(hatch none 0.5)
			(connect_pads
				(clearance 0)
			)
			(min_thickness 0.25)
			(keepout
				(tracks not_allowed)
				(vias allowed)
				(pads allowed)
				(copperpour not_allowed)
				(footprints allowed)
			)
			(placement
				(enabled no)
				(sheetname "")
			)
			(fill
				(thermal_gap 0.5)
				(thermal_bridge_width 0.5)
				(island_removal_mode 0)
			)
			(polygon
				(pts
					(xy 49.0474 -93.3069) (xy 49.8094 -93.3069) (xy 49.8094 -92.7989) (xy 49.0474 -92.7989)
				)
			)
		)
	)
)
